# BASEBOARD_FAB2 (Tioga Pass) — schematic netlist excerpt (pin names and nets, part order shuffled) for the footprints in the layout excerpt that follows; sources: Cadence DE-HDL packaged netlist, KiCad conversion of Wiwynn_Tioga_Pass_MB.brd

R7P6  RES  42.2 1.0% EMPTY  pkg 0402  page 103 : A = CLK_100M_CPU1_RC_REFCLK0_DP ; B = GND
C5P4  CAP  100UF 4V 20% X5R  pkg 0805  page 220 : A = PVDDQ_DEF ; B = GND
R6M2  RES  2 1.0% CHIP  pkg 0402  page 98 : A = M_D_CPU_VREF ; B = M_D_VREF

(kicad_pcb
	(version 20260206)
	(generator "pcbnew")
	(generator_version "10.0")
	(general
		(thickness 1.6)
		(legacy_teardrops no)
	)
	(paper "A4")
	(title_block
		(title "Wiwynn_Tioga_Pass_MB.brd")
		(comment 1 "Tioga Pass / footprints 2605-2607 of 4770")
	)
	(layers
		(0 "F.Cu" signal "TOP")
		(4 "In1.Cu" signal "L2GND")
		(6 "In2.Cu" signal "L3")
		(8 "In3.Cu" signal "L4GND")
		(10 "In4.Cu" signal "L5")
		(12 "In5.Cu" signal "L6GND")
		(14 "In6.Cu" signal "L7VCC")
		(16 "In7.Cu" signal "L8VCC")
		(18 "In8.Cu" signal "L9GND")
		(20 "In9.Cu" signal "L10")
		(22 "In10.Cu" signal "L11GND")
		(24 "In11.Cu" signal "L12")
		(26 "In12.Cu" signal "L13GND")
		(2 "B.Cu" signal "BOTTOM")
		(9 "F.Adhes" user "F.Adhesive")
		(11 "B.Adhes" user "B.Adhesive")
		(13 "F.Paste" user "Package Geometry/Pastemask Top")
		(15 "B.Paste" user "Package Geometry/Pastemask Bottom")
		(5 "F.SilkS" user "Ref Des/Silkscreen Top")
		(7 "B.SilkS" user "Ref Des/Silkscreen Bottom")
		(1 "F.Mask" user "Board Geometry/Soldermask Top")
		(3 "B.Mask" user "Board Geometry/Soldermask Bottom")
		(17 "Dwgs.User" user "User.Drawings")
		(19 "Cmts.User" user "User.Comments")
		(21 "Eco1.User" user "User.Eco1")
		(23 "Eco2.User" user "User.Eco2")
		(25 "Edge.Cuts" user "Board Geometry/Outline")
		(27 "Margin" user)
		(31 "F.CrtYd" user "Package Geometry/Place Bound Top")
		(29 "B.CrtYd" user "Package Geometry/Place Bound Bottom")
		(35 "F.Fab" user "Ref Des/Assembly Top")
		(33 "B.Fab" user "Ref Des/Assembly Bottom")
	)
	(footprint ""
		(layer "B.Cu")
		(at 273.052286 -85.06714)
		(property "Reference" "C5P4"
			(at 0 0 0)
			(layer "B.SilkS")
			(hide yes)
			(effects
				(font
					(size 1.27 1.27)
				)
				(justify mirror)
			)
		)
		(property "Value" ""
			(at 0 0 0)
			(layer "B.Fab")
			(effects
				(font
					(size 1.27 1.27)
				)
				(justify mirror)
			)
		)
		(duplicate_pad_numbers_are_jumpers no)
		(fp_poly
			(pts
				(xy 0.7239 -0.2159) (xy -0.7239 -0.2159) (xy -0.7239 1.9939) (xy 0.7239 1.9939)
			)
			(stroke
				(width 0)
				(type default)
			)
			(fill no)
			(layer "B.CrtYd")
		)
		(fp_line
			(start -0.7239 -0.2159)
			(end 0.7239 -0.2159)
			(stroke
				(width 0.1)
				(type default)
			)
			(layer "B.Fab")
		)
		(fp_line
			(start -0.7239 1.9939)
			(end -0.7239 -0.2159)
			(stroke
				(width 0.1)
				(type default)
			)
			(layer "B.Fab")
		)
		(fp_line
			(start 0.7239 -0.2159)
			(end 0.7239 1.9939)
			(stroke
				(width 0.1)
				(type default)
			)
			(layer "B.Fab")
		)
		(fp_line
			(start 0.7239 1.9939)
			(end -0.7239 1.9939)
			(stroke
				(width 0.1)
				(type default)
			)
			(layer "B.Fab")
		)
		(pad "1" smd rect
			(at 0 0 180)
			(size 1.27 1.016)
			(layers "B.Cu" "B.Mask" "B.Paste")
			(net "PVDDQ_DEF")
		)
		(pad "2" smd rect
			(at 0 1.778 180)
			(size 1.27 1.016)
			(layers "B.Cu" "B.Mask" "B.Paste")
			(net "GND")
		)
		(zone
			(layer "B.Cu")
			(hatch none 0.5)
			(connect_pads
				(clearance 0)
			)
			(min_thickness 0.25)
			(keepout
				(tracks not_allowed)
				(vias allowed)
				(pads allowed)
				(copperpour not_allowed)
				(footprints allowed)
			)
			(placement
				(enabled no)
				(sheetname "")
			)
			(fill
				(thermal_gap 0.5)
				(thermal_bridge_width 0.5)
				(island_removal_mode 0)
			)
			(polygon
				(pts
					(xy 273.687286 -84.55914) (xy 272.417286 -84.55914) (xy 272.417286 -83.79714) (xy 273.687286 -83.79714)
				)
			)
		)
	)
	(footprint ""
		(layer "B.Cu")
		(at 192.913 -134.874 180)
		(property "Reference" "R6M2"
			(at 0 0 0)
			(layer "B.SilkS")
			(hide yes)
			(effects
				(font
					(size 1.27 1.27)
				)
				(justify mirror)
			)
		)
		(property "Value" ""
			(at 0 0 0)
			(layer "B.Fab")
			(effects
				(font
					(size 1.27 1.27)
				)
				(justify mirror)
			)
		)
		(duplicate_pad_numbers_are_jumpers no)
		(fp_poly
			(pts
				(xy 0.2794 -0.1016) (xy -0.2794 -0.1016) (xy -0.2794 0.9906) (xy 0.2794 0.9906)
			)
			(stroke
				(width 0)
				(type default)
			)
			(fill no)
			(layer "B.CrtYd")
		)
		(fp_line
			(start 0.2794 0.9906)
			(end -0.2794 0.9906)
			(stroke
				(width 0.1)
				(type default)
			)
			(layer "B.Fab")
		)
		(fp_line
			(start 0.2794 -0.1016)
			(end 0.2794 0.9906)
			(stroke
				(width 0.1)
				(type default)
			)
			(layer "B.Fab")
		)
		(fp_line
			(start -0.2794 0.9906)
			(end -0.2794 -0.1016)
			(stroke
				(width 0.1)
				(type default)
			)
			(layer "B.Fab")
		)
		(fp_line
			(start -0.2794 -0.1016)
			(end 0.2794 -0.1016)
			(stroke
				(width 0.1)
				(type default)
			)
			(layer "B.Fab")
		)
		(pad "1" smd rect
			(at 0 0)
			(size 0.508 0.508)
			(layers "B.Cu" "B.Mask" "B.Paste")
			(net "M_D_CPU_VREF")
		)
		(pad "2" smd rect
			(at 0 0.889)
			(size 0.508 0.508)
			(layers "B.Cu" "B.Mask" "B.Paste")
			(net "M_D_VREF")
		)
		(zone
			(layer "B.Cu")
			(hatch none 0.5)
			(connect_pads
				(clearance 0)
			)
			(min_thickness 0.25)
			(keepout
				(tracks not_allowed)
				(vias allowed)
				(pads allowed)
				(copperpour not_allowed)
				(footprints allowed)
			)
			(placement
				(enabled no)
				(sheetname "")
			)
			(fill
				(thermal_gap 0.5)
				(thermal_bridge_width 0.5)
				(island_removal_mode 0)
			)
			(polygon
				(pts
					(xy 192.659 -135.509) (xy 193.167 -135.509) (xy 193.167 -135.128) (xy 192.659 -135.128)
				)
			)
		)
		(zone
			(layer "B.Cu")
			(hatch none 0.5)
			(connect_pads
				(clearance 0)
			)
			(min_thickness 0.25)
			(keepout
				(tracks allowed)
				(vias not_allowed)
				(pads allowed)
				(copperpour not_allowed)
				(footprints allowed)
			)
			(placement
				(enabled no)
				(sheetname "")
			)
			(fill
				(thermal_gap 0.5)
				(thermal_bridge_width 0.5)
				(island_removal_mode 0)
			)
			(polygon
				(pts
					(xy 192.659 -135.128) (xy 193.167 -135.128) (xy 193.167 -135.509) (xy 192.659 -135.509)
				)
			)
		)
	)
	(footprint ""
		(layer "B.Cu")
		(at 162.7886 -80.3402 90)
		(property "Reference" "R7P6"
			(at 0 0 90)
			(layer "B.SilkS")
			(hide yes)
			(effects
				(font
					(size 1.27 1.27)
				)
				(justify mirror)
			)
		)
		(property "Value" ""
			(at 0 0 90)
			(layer "B.Fab")
			(effects
				(font
					(size 1.27 1.27)
				)
				(justify mirror)
			)
		)
		(duplicate_pad_numbers_are_jumpers no)
		(fp_poly
			(pts
				(xy 0.2794 -0.1016) (xy -0.2794 -0.1016) (xy -0.2794 0.9906) (xy 0.2794 0.9906)
			)
			(stroke
				(width 0)
				(type default)
			)
			(fill no)
			(layer "B.CrtYd")
		)
		(fp_line
			(start 0.2794 -0.1016)
			(end 0.2794 0.9906)
			(stroke
				(width 0.1)
				(type default)
			)
			(layer "B.Fab")
		)
		(fp_line
			(start -0.2794 -0.1016)
			(end 0.2794 -0.1016)
			(stroke
				(width 0.1)
				(type default)
			)
			(layer "B.Fab")
		)
		(fp_line
			(start 0.2794 0.9906)
			(end -0.2794 0.9906)
			(stroke
				(width 0.1)
				(type default)
			)
			(layer "B.Fab")
		)
		(fp_line
			(start -0.2794 0.9906)
			(end -0.2794 -0.1016)
			(stroke
				(width 0.1)
				(type default)
			)
			(layer "B.Fab")
		)
		(pad "1" smd rect
			(at 0 0 270)
			(size 0.508 0.508)
			(layers "B.Cu" "B.Mask" "B.Paste")
			(net "CLK_100M_CPU1_RC_REFCLK0_DP")
		)
		(pad "2" smd rect
			(at 0 0.889 270)
			(size 0.508 0.508)
			(layers "B.Cu" "B.Mask" "B.Paste")
			(net "GND")
		)
		(zone
			(layer "B.Cu")
			(hatch none 0.5)
			(connect_pads
				(clearance 0)
			)
			(min_thickness 0.25)
			(keepout
				(tracks allowed)
				(vias not_allowed)
				(pads allowed)
				(copperpour not_allowed)
				(footprints allowed)
			)
			(placement
				(enabled no)
				(sheetname "")
			)
			(fill
				(thermal_gap 0.5)
				(thermal_bridge_width 0.5)
				(island_removal_mode 0)
			)
			(polygon
				(pts
					(xy 163.0426 -80.5942) (xy 163.0426 -80.0862) (xy 163.4236 -80.0862) (xy 163.4236 -80.5942)
				)
			)
		)
		(zone
			(layer "B.Cu")
			(hatch none 0.5)
			(connect_pads
				(clearance 0)
			)
			(min_thickness 0.25)
			(keepout
				(tracks not_allowed)
				(vias allowed)
				(pads allowed)
				(copperpour not_allowed)
				(footprints allowed)
			)
			(placement
				(enabled no)
				(sheetname "")
			)
			(fill
				(thermal_gap 0.5)
				(thermal_bridge_width 0.5)
				(island_removal_mode 0)
			)
			(polygon
				(pts
					(xy 163.4236 -80.5942) (xy 163.4236 -80.0862) (xy 163.0426 -80.0862) (xy 163.0426 -80.5942)
				)
			)
		)
	)
)
